FILE_TYPE=MULTI_PHYS_TABLE;
PART 'TTL1G08'
{=========================================================================================================================================================================}
:VALUE        | PACK_TYPE | MATERIAL | PART_NUMBER     = EnvComp | PART_NUMBER  | JEDEC_TYPE     | CLASS | DESCRIPTION          | HEIGHT    | COMPONENT_TYPE | LEAD_LENGTH| LPID   | SPEED_URL | Status |RPL| AML | Bus_Unit | Days ;
{=========================================================================================================================================================================}
'NC7SZ08'     | 'SOTLF'   | 'IC'     | 'D10321-001'(!) = 'YES;YES;CNC;CNC;ok;CIP' | 'D10321-001' | 'SSOP5_53_65MA'| 'IC'  | 'SINGLE 2-INPUT AND' | '0.043 IN'| 'SUB50'        | '' | '374' | 'http://speed.intel.com:8081/speed/module/pdm/item/pdm_item_detail_direct.asp?item_cde=D10321-001&item_rev=01&url_param=unused' | 'Conditional' | 'YES' | '6' | 'SMO_IC' | '49' 
'NC7SZ08'     | 'SOTLF'   | 'EMPTY'  | 'D10321-001'(!) = 'YES;YES;CNC;CNC;ok;CIP' | 'D10321-001' | 'SSOP5_53_65MA'| 'IO'  | 'SINGLE 2-INPUT AND' | '0.043 IN'| 'SUB50'        | '' | '374' | 'http://speed.intel.com:8081/speed/module/pdm/item/pdm_item_detail_direct.asp?item_cde=D10321-001&item_rev=01&url_param=unused' | 'Conditional' | 'YES' | '6' | 'SMO_IC' | '49' 
END_PART
END.
